# S9S_MB_2U (Grand Teton) — schematic netlist excerpt (pin names and nets, part order shuffled) for the footprints in the layout excerpt that follows; sources: Cadence DE-HDL packaged netlist, KiCad conversion of 03242023_DA0F0TMBIJ0_F0T_Motherboard_J_brd_V01_OCP.brd

J41  SCONN168_ME1016810202011  IO  pkg CON_F168S2H7D_P0-6W2-95_LUH  page 240
  GND_A1  = SMB_OCP_SFF_3V3AUX_SCL_R0
  GND_A2  = SMB_OCP_SFF_3V3AUX_SDA_R0
  GND_A3  = SMB_HOST_3V3AUX_SCL_R0
  GND_A4  = SMB_HOST_3V3AUX_SDA_R0
  GND_A5  = SMB_VR_3V3AUX_SCL_R0
  GND_A6  = SMB_VR_3V3AUX_SDA_R0
  SMCLK  = SMB_SML1_PMBUS_3V3AUX_PCH_SCL_R
  SMDAT  = SMB_SML1_PMBUS_3V3AUX_PCH_SDA_R
  \smrst#\  = I3C_BMC_SWB_SCL
  \prsnta#\  = I3C_BMC_SWB_SDA
  \perst1#\  = SMB_OCP_V3_2_3V3AUX_SCL_R0
  \prsntb2#\  = SMB_OCP_V3_2_3V3AUX_SDA_R0
  GND_A13  = GND
  REFCLKN1  = CLK_100M_BMC_P3E_DP_R
  REFCLKP1  = CLK_100M_BMC_P3E_DN_R
  GND_A16  = GND
  PERN0  = P3E_PCH_BMC_TX_C_DP
  PERP0  = P3E_PCH_BMC_TX_C_DN
  GND_A19  = GND
  PERN1  = P3E_PCH_BMC_RX_DP
  PERP1  = P3E_PCH_BMC_RX_DN
  GND_A22  = GND
  PERN2  = SMB_PCIE0_3V3AUX_SCL
  PERP2  = SMB_PCIE0_3V3AUX_SDA
  GND_A25  = SMB_SML0_3V3AUX_SCL_R1
  PERN3  = SMB_SML0_3V3AUX_SDA_R1
  PERP3  = SMB_1_PLD_3V3AUX_SCL_R3
  GND_A28  = SMB_1_PLD_3V3AUX_SDA_R3
  GND_A29  = SMB_FAN_3V3AUX_SCL
  PERN4  = SMB_FAN_3V3AUX_SDA
  PERP4  = SMB_PCIE2_3V3AUX_SCL_R0
  GND_A32  = SMB_PCIE2_3V3AUX_SDA_R0
  PERN5  = GND
  PERP5  = JTAG_BMC_TCK
  GND_A35  = JTAG_BMC_TMS
  PERN6  = JTAG_BMC_TDI
  PERP6  = JTAG_BMC_TDO
  GND_A38  = SMB_PCIE3_3V3AUX_SCL_R
  PERN7  = SMB_PCIE3_3V3AUX_SDA_R
  PERP7  = SMB_S3M_CPU_3V3AUX_SCL_R0
  GND_A41  = SMB_S3M_CPU_3V3AUX_SDA_R0
  \prsntb1#\  = GND
  GND_A43  = FM_JTAG_BMC_MUX_SEL_FROM_BMC_R2
  PERN8  = PWRGD_PS_PWROK_R
  PERP8  = TP_HPM_STBY_EN
  GND_A46  = RST_MB_STBY_N
  PERN9  = FM_BMC_PWRBTN_OUT_R_N
  PERP9  = PWRGD_SYS_PWROK
  GND_A49  = JTAG_BMC_DBP_PREQ_N
  PERN10  = JTAG_DBP_BMC_PRDY_N
  PERP10  = RST_PLTRST_B_N
  GND_A52  = FM_UARTSW_MSB_R
  PERN11  = ROT_P1_RST_IND_N
  PERP11  = FM_BMC_INTRUDER_N
  GND_A55  = FM_UARTSW_LSB_R
  PERN12  = IRQ0_A57
  PERP12  = FM_SCM_PRSNT1_N
  GND_A58  = GND
  PERN13  = USB3_PCH_RX_DP<4>
  PERP13  = USB3_PCH_RX_DN<4>
  GND_A61  = GND
  PERN14  = TP_PCIE_HPM_RXP<1>
  PERP14  = TP_PCIE_HPM_RXN<1>
  GND_A64  = GND
  PERN15  = P2E_MB_BMC_RX_BUF_DP<0>
  PERP15  = P2E_MB_BMC_RX_BUF_DN<0>
  GND_A67  = GND
  USB_DATN  = CLK_100M_BMC_RC_DP
  USB_DATP  = CLK_100M_BMC_RC_DN
  \pwrbrk0#\  = GND
  \+12v_edge_b1\  = ESPI_HOST_LPC_BMC_CLK
  \+12v_edge_b2\  = ESPI_HOST_LPC_BMC_LFRAME_N
  \+12v_edge_b3\  = IRQ_ESPI_LPC_SERIRQ_ALERT_R_N
  \+12v_edge_b4\  = ESPI_BMC_LPC_RST_N
  \+12v_edge_b5\  = ESPI_LPC_LAD0_IO0
  \+12v_edge_b6\  = ESPI_LPC_LAD0_IO1
  \bif0#\  = ESPI_LPC_LAD0_IO2
  \bif1#\  = ESPI_LPC_LAD0_IO3
  \bif2#\  = FM_LPC_ESPI_SEL
  \perst0#\  = GND
  \+3.3v_edge\  = SPI_SYS_CLK
  AUX_PWR_EN  = SPI_SYS_CS0_N
  GND_B13  = SPI_SYS_MOSI
  REFCLKN0  = SPI_SYS_MISO
  REFCLKP0  = SPI_SYS_WP_IO2
  GND_B16  = SPI_SYS_HOLD_IO3
  PETN0  = GND
  PETP0  = CLK_50M_RMII_BMC_OCP
  GND_B19  = RMII_OCP_BMC_CRSDV
  PETN1  = RMII_BMC_OCP_TX_EN
  PETP1  = RMII_BMC_OCP_TXD_0
  GND_B22  = RMII_BMC_OCP_TXD_1
  PETN2  = RMII_BMC_OCP_RX_ER
  PETP2  = RMII_OCP_BMC_RXD_0
  GND_B25  = RMII_OCP_BMC_RXD_1
  PETN3  = GND
  PETP3  = PECI_BMC
  GND_B28  = PVCCIO_PECI_BMC
  GND_B29  = SGPIO_DO_0
  PETN4  = SGPIO_CLK_0
  PETP4  = SGPIO_DI_0
  GND_B32  = SGPIO_LD_0
  PETN5  = GND
  PETP5  = SGPIO_DO_1
  GND_B35  = SGPIO_CLK_1
  PETN6  = SGPIO_DI_1
  PETP6  = SGPIO_LD_1
  GND_B38  = GND
  PETN7  = RST_SGPIO_RESET_N
  PETP7  = IRQ_SGPIO_INTR_N
  GND_B41  = P3V_BAT_R1
  \prsntb0#\  = FM_AC_PWR_BTN_N
  GND_B43  = TP_SPI_2_PLD_CLK
  PETN8  = TP_SPI_2_PLD_CS_N
  PETP8  = TP_SPI_2_PLD_IO0
  GND_B46  = TP_SPI_2_PLD_IO1
  PETN9  = TP_SPI_2_PLD_IO2
  PETP9  = TP_SPI_2_PLD_IO3
  GND_B49  = GND
  PETN10  = USB2_HOST_BMC_B_DP
  PETP10  = USB2_HOST_BMC_B_DN
  GND_B52  = GND
  PETN11  = USB2_8_DP
  PETP11  = USB2_8_DN
  GND_B55  = GND
  PETN12  = USB2_HUB_2_BUF_EXT_DP
  PETP12  = USB2_HUB_2_BUF_EXT_DN
  GND_B58  = GND
  PETN13  = USB3_PCH_TX_BUF_C_DP<4>
  PETP13  = USB3_PCH_TX_BUF_C_DN<4>
  GND_B61  = GND
  PETN14  = TP_PCIE_HPM_TXP<1>
  PETP14  = TP_PCIE_HPM_TXN<1>
  GND_B64  = GND
  PETN15  = P2E_MB_BMC_TX_C_DP<0>
  PETP15  = P2E_MB_BMC_TX_C_DN<0>
  GND_B67  = GND
  RFU1_NC_B68  = TP_PCIE_HPM_TXP<3>
  RFU1_NC_B69  = TP_PCIE_HPM_TXN<3>
  \prsntb3#\  = GND
  G1  = GND
  G2  = GND
  G3  = GND
  G4  = GND
  G5  = GND
  \perst2#\  = P12V_SCM
  \perst3#\  = P12V_SCM
  \wake#\  = GND
  RBT_ARB_IN  = GND
  RBT_ARB_OUT  = I3C_SPD_DDRABCD_CPU0_BMC_R_SCL
  SLOT_ID1  = I3C_SPD_DDRABCD_CPU0_BMC_R_SDA
  RBT_TX_EN  = I3C_SPD_DDREFGH_CPU0_BMC_R_SCL
  RBT_TXD1  = I3C_SPD_DDREFGH_CPU0_BMC_R_SDA
  RBT_TXD0  = I3C_SPD_DDRABCD_CPU1_BMC_R_SCL
  GND_OA10  = I3C_SPD_DDRABCD_CPU1_BMC_R_SDA
  REFCLKN3  = I3C_SPD_DDREFGH_CPU1_BMC_R_SCL
  REFCLKP3  = I3C_SPD_DDREFGH_CPU1_BMC_R_SDA
  GND_OA13  = GND
  RBT_CLK_IN  = VIRTUAL_RESEAT
  NIC_PWR_GOOD  = P12V_SCM
  MAIN_PWR_EN  = P12V_SCM
  \ld#\  = PRSNT0_N
  DATA_IN  = GND
  DATA_OUT  = UART_BMC_BIC_TX
  CLK  = UART_BMC_BIC_BUF_RX
  SLOT_ID0  = GND
  RBT_RXD1  = USB2_7_R_DP
  RBT_RXD0  = USB2_7_R_DN
  GND_OB10  = GND
  REFCLKN2  = RST_SRST_PLD_BMC_N
  REFCLKP2  = SPI_TPM_CS_N
  GND_OB13  = H_CPU_CATERR_LVC2_BMC_N
  RBT_CRS_DV  = FM_SOL_UART_CH_SEL_R

(kicad_pcb
	(version 20260206)
	(generator "pcbnew")
	(generator_version "10.0")
	(general
		(thickness 1.6)
		(legacy_teardrops no)
	)
	(paper "A4")
	(title_block
		(title "03242023_DA0F0TMBIJ0_F0T_Motherboard_J_brd_V01_OCP.brd")
		(comment 1 "Grand Teton / footprint 3077 of 6105 (J41), pads 175-175 of 175")
	)
	(layers
		(0 "F.Cu" signal "TOP")
		(4 "In1.Cu" signal "GND")
		(6 "In2.Cu" signal "IN1")
		(8 "In3.Cu" signal "GND1")
		(10 "In4.Cu" signal "IN2")
		(12 "In5.Cu" signal "GND2")
		(14 "In6.Cu" signal "IN3")
		(16 "In7.Cu" signal "GND3")
		(18 "In8.Cu" signal "VCC")
		(20 "In9.Cu" signal "VCC1")
		(22 "In10.Cu" signal "GND4")
		(24 "In11.Cu" signal "IN4")
		(26 "In12.Cu" signal "GND5")
		(28 "In13.Cu" signal "IN5")
		(30 "In14.Cu" signal "GND6")
		(32 "In15.Cu" signal "IN6")
		(34 "In16.Cu" signal "GND7")
		(2 "B.Cu" signal "BOTTOM")
		(9 "F.Adhes" user "F.Adhesive")
		(11 "B.Adhes" user "B.Adhesive")
		(13 "F.Paste" user "Package Geometry/Pastemask Top")
		(15 "B.Paste" user "Package Geometry/Pastemask Bottom")
		(5 "F.SilkS" user "Ref Des/Silkscreen Top")
		(7 "B.SilkS" user "Ref Des/Silkscreen Bottom")
		(1 "F.Mask" user "Board Geometry/Soldermask Top")
		(3 "B.Mask" user "Board Geometry/Soldermask Bottom")
		(17 "Dwgs.User" user "User.Drawings")
		(19 "Cmts.User" user "User.Comments")
		(21 "Eco1.User" user "User.Eco1")
		(23 "Eco2.User" user "User.Eco2")
		(25 "Edge.Cuts" user "Board Geometry/Outline")
		(27 "Margin" user)
		(31 "F.CrtYd" user "Package Geometry/Place Bound Top")
		(29 "B.CrtYd" user "Package Geometry/Place Bound Bottom")
		(35 "F.Fab" user "Ref Des/Assembly Top")
		(33 "B.Fab" user "Ref Des/Assembly Bottom")
	)
	(footprint ""
		(layer "F.Cu")
		(at 160.402016 -10.850118 -90)
		(property "Reference" "J41"
			(at -12.075414 24.511762 0)
			(unlocked yes)
			(layer "F.SilkS")
			(effects
				(font
					(size 0.7874 0.5842)
					(thickness 0.1524)
				)
				(justify left)
			)
		)
		(property "Value" ""
			(at 0 0 270)
			(layer "F.Fab")
			(effects
				(font
					(size 1.27 1.27)
				)
			)
		)
		(duplicate_pad_numbers_are_jumpers no)
		(pad "OB14" smd rect
			(at -5.700014 -22.86 180)
			(size 0.381 1.4478)
			(layers "F.Cu" "F.Mask" "F.Paste")
			(net "FM_SOL_UART_CH_SEL_R")
		)
	)
)
